# BASEBOARD_FAB2 (Tioga Pass) — schematic netlist excerpt (pin names and nets, part order shuffled) for the footprints in the layout excerpt that follows; sources: Cadence DE-HDL packaged netlist, KiCad conversion of Wiwynn_Tioga_Pass_MB.brd

R3P12  RES  100.0K 1% CHIP  pkg 0402  page 211 : A = VR_FET_SW_P12V_STBY_PVCCIO_CPU0 ; B = VR_PVCCIO_CPU0_VINSEN
C2T22  CAP  10UF 16V 10% X6S  pkg 0805  page 101 : A = P3V3_STBY_MNG ; B = GND
R9E14  RES  0.0 5% EMPTY  pkg 0402  page 157 : A = FM_TPM_PRES_RST_N ; B = FM_BMC_ENABLE_N

(kicad_pcb
	(version 20260206)
	(generator "pcbnew")
	(generator_version "10.0")
	(general
		(thickness 1.6)
		(legacy_teardrops no)
	)
	(paper "A4")
	(title_block
		(title "Wiwynn_Tioga_Pass_MB.brd")
		(comment 1 "Tioga Pass / footprints 4240-4242 of 4770")
	)
	(layers
		(0 "F.Cu" signal "TOP")
		(4 "In1.Cu" signal "L2GND")
		(6 "In2.Cu" signal "L3")
		(8 "In3.Cu" signal "L4GND")
		(10 "In4.Cu" signal "L5")
		(12 "In5.Cu" signal "L6GND")
		(14 "In6.Cu" signal "L7VCC")
		(16 "In7.Cu" signal "L8VCC")
		(18 "In8.Cu" signal "L9GND")
		(20 "In9.Cu" signal "L10")
		(22 "In10.Cu" signal "L11GND")
		(24 "In11.Cu" signal "L12")
		(26 "In12.Cu" signal "L13GND")
		(2 "B.Cu" signal "BOTTOM")
		(9 "F.Adhes" user "F.Adhesive")
		(11 "B.Adhes" user "B.Adhesive")
		(13 "F.Paste" user "Package Geometry/Pastemask Top")
		(15 "B.Paste" user "Package Geometry/Pastemask Bottom")
		(5 "F.SilkS" user "Ref Des/Silkscreen Top")
		(7 "B.SilkS" user "Ref Des/Silkscreen Bottom")
		(1 "F.Mask" user "Board Geometry/Soldermask Top")
		(3 "B.Mask" user "Board Geometry/Soldermask Bottom")
		(17 "Dwgs.User" user "User.Drawings")
		(19 "Cmts.User" user "User.Comments")
		(21 "Eco1.User" user "User.Eco1")
		(23 "Eco2.User" user "User.Eco2")
		(25 "Edge.Cuts" user "Board Geometry/Outline")
		(27 "Margin" user)
		(31 "F.CrtYd" user "Package Geometry/Place Bound Top")
		(29 "B.CrtYd" user "Package Geometry/Place Bound Bottom")
		(35 "F.Fab" user "Ref Des/Assembly Top")
		(33 "B.Fab" user "Ref Des/Assembly Bottom")
	)
	(footprint ""
		(layer "B.Cu")
		(at 456.787758 -32.062674)
		(property "Reference" "R9E14"
			(at 0 0 0)
			(layer "B.SilkS")
			(hide yes)
			(effects
				(font
					(size 1.27 1.27)
				)
				(justify mirror)
			)
		)
		(property "Value" ""
			(at 0 0 0)
			(layer "B.Fab")
			(effects
				(font
					(size 1.27 1.27)
				)
				(justify mirror)
			)
		)
		(duplicate_pad_numbers_are_jumpers no)
		(fp_poly
			(pts
				(xy 0.2794 -0.1016) (xy -0.2794 -0.1016) (xy -0.2794 0.9906) (xy 0.2794 0.9906)
			)
			(stroke
				(width 0)
				(type default)
			)
			(fill no)
			(layer "B.CrtYd")
		)
		(fp_line
			(start -0.2794 -0.1016)
			(end 0.2794 -0.1016)
			(stroke
				(width 0.1)
				(type default)
			)
			(layer "B.Fab")
		)
		(fp_line
			(start -0.2794 0.9906)
			(end -0.2794 -0.1016)
			(stroke
				(width 0.1)
				(type default)
			)
			(layer "B.Fab")
		)
		(fp_line
			(start 0.2794 -0.1016)
			(end 0.2794 0.9906)
			(stroke
				(width 0.1)
				(type default)
			)
			(layer "B.Fab")
		)
		(fp_line
			(start 0.2794 0.9906)
			(end -0.2794 0.9906)
			(stroke
				(width 0.1)
				(type default)
			)
			(layer "B.Fab")
		)
		(pad "1" smd rect
			(at 0 0 180)
			(size 0.508 0.508)
			(layers "B.Cu" "B.Mask" "B.Paste")
			(net "FM_TPM_PRES_RST_N")
		)
		(pad "2" smd rect
			(at 0 0.889 180)
			(size 0.508 0.508)
			(layers "B.Cu" "B.Mask" "B.Paste")
			(net "FM_BMC_ENABLE_N")
		)
		(zone
			(layer "B.Cu")
			(hatch none 0.5)
			(connect_pads
				(clearance 0)
			)
			(min_thickness 0.25)
			(keepout
				(tracks allowed)
				(vias not_allowed)
				(pads allowed)
				(copperpour not_allowed)
				(footprints allowed)
			)
			(placement
				(enabled no)
				(sheetname "")
			)
			(fill
				(thermal_gap 0.5)
				(thermal_bridge_width 0.5)
				(island_removal_mode 0)
			)
			(polygon
				(pts
					(xy 457.041758 -31.808674) (xy 456.533758 -31.808674) (xy 456.533758 -31.427674) (xy 457.041758 -31.427674)
				)
			)
		)
		(zone
			(layer "B.Cu")
			(hatch none 0.5)
			(connect_pads
				(clearance 0)
			)
			(min_thickness 0.25)
			(keepout
				(tracks not_allowed)
				(vias allowed)
				(pads allowed)
				(copperpour not_allowed)
				(footprints allowed)
			)
			(placement
				(enabled no)
				(sheetname "")
			)
			(fill
				(thermal_gap 0.5)
				(thermal_bridge_width 0.5)
				(island_removal_mode 0)
			)
			(polygon
				(pts
					(xy 457.041758 -31.427674) (xy 456.533758 -31.427674) (xy 456.533758 -31.808674) (xy 457.041758 -31.808674)
				)
			)
		)
	)
	(footprint ""
		(layer "B.Cu")
		(at 351.8662 -87.503 -90)
		(property "Reference" "R3P12"
			(at 0 0 90)
			(layer "B.SilkS")
			(hide yes)
			(effects
				(font
					(size 1.27 1.27)
				)
				(justify mirror)
			)
		)
		(property "Value" ""
			(at 0 0 90)
			(layer "B.Fab")
			(effects
				(font
					(size 1.27 1.27)
				)
				(justify mirror)
			)
		)
		(duplicate_pad_numbers_are_jumpers no)
		(fp_poly
			(pts
				(xy 0.2794 -0.1016) (xy -0.2794 -0.1016) (xy -0.2794 0.9906) (xy 0.2794 0.9906)
			)
			(stroke
				(width 0)
				(type default)
			)
			(fill no)
			(layer "B.CrtYd")
		)
		(fp_line
			(start -0.2794 0.9906)
			(end -0.2794 -0.1016)
			(stroke
				(width 0.1)
				(type default)
			)
			(layer "B.Fab")
		)
		(fp_line
			(start 0.2794 0.9906)
			(end -0.2794 0.9906)
			(stroke
				(width 0.1)
				(type default)
			)
			(layer "B.Fab")
		)
		(fp_line
			(start -0.2794 -0.1016)
			(end 0.2794 -0.1016)
			(stroke
				(width 0.1)
				(type default)
			)
			(layer "B.Fab")
		)
		(fp_line
			(start 0.2794 -0.1016)
			(end 0.2794 0.9906)
			(stroke
				(width 0.1)
				(type default)
			)
			(layer "B.Fab")
		)
		(pad "1" smd rect
			(at 0 0 90)
			(size 0.508 0.508)
			(layers "B.Cu" "B.Mask" "B.Paste")
			(net "VR_FET_SW_P12V_STBY_PVCCIO_CPU0")
		)
		(pad "2" smd rect
			(at 0 0.889 90)
			(size 0.508 0.508)
			(layers "B.Cu" "B.Mask" "B.Paste")
			(net "VR_PVCCIO_CPU0_VINSEN")
		)
		(zone
			(layer "B.Cu")
			(hatch none 0.5)
			(connect_pads
				(clearance 0)
			)
			(min_thickness 0.25)
			(keepout
				(tracks not_allowed)
				(vias allowed)
				(pads allowed)
				(copperpour not_allowed)
				(footprints allowed)
			)
			(placement
				(enabled no)
				(sheetname "")
			)
			(fill
				(thermal_gap 0.5)
				(thermal_bridge_width 0.5)
				(island_removal_mode 0)
			)
			(polygon
				(pts
					(xy 351.2312 -87.249) (xy 351.2312 -87.757) (xy 351.6122 -87.757) (xy 351.6122 -87.249)
				)
			)
		)
		(zone
			(layer "B.Cu")
			(hatch none 0.5)
			(connect_pads
				(clearance 0)
			)
			(min_thickness 0.25)
			(keepout
				(tracks allowed)
				(vias not_allowed)
				(pads allowed)
				(copperpour not_allowed)
				(footprints allowed)
			)
			(placement
				(enabled no)
				(sheetname "")
			)
			(fill
				(thermal_gap 0.5)
				(thermal_bridge_width 0.5)
				(island_removal_mode 0)
			)
			(polygon
				(pts
					(xy 351.6122 -87.249) (xy 351.6122 -87.757) (xy 351.2312 -87.757) (xy 351.2312 -87.249)
				)
			)
		)
	)
	(footprint ""
		(layer "B.Cu")
		(at 483.19436 -28.547314)
		(property "Reference" "C2T22"
			(at 0 0 0)
			(layer "B.SilkS")
			(hide yes)
			(effects
				(font
					(size 1.27 1.27)
				)
				(justify mirror)
			)
		)
		(property "Value" ""
			(at 0 0 0)
			(layer "B.Fab")
			(effects
				(font
					(size 1.27 1.27)
				)
				(justify mirror)
			)
		)
		(duplicate_pad_numbers_are_jumpers no)
		(fp_poly
			(pts
				(xy 0.7239 -0.2159) (xy -0.7239 -0.2159) (xy -0.7239 1.9939) (xy 0.7239 1.9939)
			)
			(stroke
				(width 0)
				(type default)
			)
			(fill no)
			(layer "B.CrtYd")
		)
		(fp_line
			(start -0.7239 -0.2159)
			(end 0.7239 -0.2159)
			(stroke
				(width 0.1)
				(type default)
			)
			(layer "B.Fab")
		)
		(fp_line
			(start -0.7239 1.9939)
			(end -0.7239 -0.2159)
			(stroke
				(width 0.1)
				(type default)
			)
			(layer "B.Fab")
		)
		(fp_line
			(start 0.7239 -0.2159)
			(end 0.7239 1.9939)
			(stroke
				(width 0.1)
				(type default)
			)
			(layer "B.Fab")
		)
		(fp_line
			(start 0.7239 1.9939)
			(end -0.7239 1.9939)
			(stroke
				(width 0.1)
				(type default)
			)
			(layer "B.Fab")
		)
		(pad "1" smd rect
			(at 0 0 180)
			(size 1.27 1.016)
			(layers "B.Cu" "B.Mask" "B.Paste")
			(net "P3V3_STBY_MNG")
		)
		(pad "2" smd rect
			(at 0 1.778 180)
			(size 1.27 1.016)
			(layers "B.Cu" "B.Mask" "B.Paste")
			(net "GND")
		)
		(zone
			(layer "B.Cu")
			(hatch none 0.5)
			(connect_pads
				(clearance 0)
			)
			(min_thickness 0.25)
			(keepout
				(tracks not_allowed)
				(vias allowed)
				(pads allowed)
				(copperpour not_allowed)
				(footprints allowed)
			)
			(placement
				(enabled no)
				(sheetname "")
			)
			(fill
				(thermal_gap 0.5)
				(thermal_bridge_width 0.5)
				(island_removal_mode 0)
			)
			(polygon
				(pts
					(xy 483.82936 -28.039314) (xy 482.55936 -28.039314) (xy 482.55936 -27.277314) (xy 483.82936 -27.277314)
				)
			)
		)
	)
)
